(kicad_pcb
	(version 20260206)
	(generator "pcbnew")
	(generator_version "10.0")
	(general
		(thickness 1.6)
		(legacy_teardrops no)
	)
	(paper "A4")
	(title_block
		(title "01162023_DA0F0TEBIF0_F0T_Expander_BD_F_brd_V02_OCP.brd")
		(comment 1 "Grand Teton / footprints 8895-8903 of 9728")
	)
	(layers
		(0 "F.Cu" signal "TOP")
		(4 "In1.Cu" signal "GND")
		(6 "In2.Cu" signal "VCC")
		(8 "In3.Cu" signal "VCC1")
		(10 "In4.Cu" signal "GND1")
		(12 "In5.Cu" signal "IN1")
		(14 "In6.Cu" signal "GND2")
		(16 "In7.Cu" signal "IN2")
		(18 "In8.Cu" signal "GND3")
		(20 "In9.Cu" signal "IN3")
		(22 "In10.Cu" signal "GND4")
		(24 "In11.Cu" signal "IN4")
		(26 "In12.Cu" signal "GND5")
		(28 "In13.Cu" signal "IN5")
		(30 "In14.Cu" signal "GND6")
		(32 "In15.Cu" signal "IN6")
		(34 "In16.Cu" signal "GND7")
		(2 "B.Cu" signal "BOTTOM")
		(9 "F.Adhes" user "F.Adhesive")
		(11 "B.Adhes" user "B.Adhesive")
		(13 "F.Paste" user "Package Geometry/Pastemask Top")
		(15 "B.Paste" user "Package Geometry/Pastemask Bottom")
		(5 "F.SilkS" user "Ref Des/Silkscreen Top")
		(7 "B.SilkS" user "Ref Des/Silkscreen Bottom")
		(1 "F.Mask" user "Board Geometry/Soldermask Top")
		(3 "B.Mask" user "Board Geometry/Soldermask Bottom")
		(17 "Dwgs.User" user "User.Drawings")
		(19 "Cmts.User" user "User.Comments")
		(21 "Eco1.User" user "User.Eco1")
		(23 "Eco2.User" user "User.Eco2")
		(25 "Edge.Cuts" user "Board Geometry/Outline")
		(27 "Margin" user)
		(31 "F.CrtYd" user "Package Geometry/Place Bound Top")
		(29 "B.CrtYd" user "Package Geometry/Place Bound Bottom")
		(35 "F.Fab" user "Ref Des/Assembly Top")
		(33 "B.Fab" user "Ref Des/Assembly Bottom")
	)
	(footprint ""
		(layer "B.Cu")
		(at 122.689366 -313.620404)
		(property "Reference" "R5788"
			(at 0 0 0)
			(layer "B.SilkS")
			(hide yes)
			(effects
				(font
					(size 1.27 1.27)
				)
				(justify mirror)
			)
		)
		(property "Value" ""
			(at 0 0 0)
			(layer "B.Fab")
			(effects
				(font
					(size 1.27 1.27)
				)
				(justify mirror)
			)
		)
		(duplicate_pad_numbers_are_jumpers no)
		(fp_line
			(start -2.576322 -1.1303)
			(end -2.576322 1.1303)
			(stroke
				(width 0.1524)
				(type default)
			)
			(layer "B.SilkS")
		)
		(fp_line
			(start -2.576322 1.1303)
			(end 2.576322 1.1303)
			(stroke
				(width 0.1524)
				(type default)
			)
			(layer "B.SilkS")
		)
		(fp_line
			(start 2.576322 -1.1303)
			(end -2.576322 -1.1303)
			(stroke
				(width 0.1524)
				(type default)
			)
			(layer "B.SilkS")
		)
		(fp_line
			(start 2.576322 1.1303)
			(end 2.576322 -1.1303)
			(stroke
				(width 0.1524)
				(type default)
			)
			(layer "B.SilkS")
		)
		(fp_line
			(start -1.649984 -0.899922)
			(end 1.649984 -0.899922)
			(stroke
				(width 0.1)
				(type default)
			)
			(layer "B.Fab")
		)
		(fp_line
			(start -1.649984 0.899922)
			(end -1.649984 -0.899922)
			(stroke
				(width 0.1)
				(type default)
			)
			(layer "B.Fab")
		)
		(fp_line
			(start 1.649984 -0.899922)
			(end 1.649984 0.899922)
			(stroke
				(width 0.1)
				(type default)
			)
			(layer "B.Fab")
		)
		(fp_line
			(start 1.649984 0.899922)
			(end -1.649984 0.899922)
			(stroke
				(width 0.1)
				(type default)
			)
			(layer "B.Fab")
		)
		(pad "1A" smd rect
			(at 1.700022 0 180)
			(size 1.4986 2.0066)
			(layers "B.Cu" "B.Mask" "B.Paste")
			(net "P0V8_PEX1")
		)
		(pad "1B" smd rect
			(at 1.077722 0 180)
			(size 0.254 0.508)
			(layers "B.Cu" "B.Mask" "B.Paste")
			(net "P0V8_PEX1")
		)
		(pad "2A" smd rect
			(at -1.700022 0 180)
			(size 1.4986 2.0066)
			(layers "B.Cu" "B.Mask" "B.Paste")
			(net "P0V8_SERDES_VDDA_PEX1")
		)
		(pad "2B" smd rect
			(at -1.077722 0 180)
			(size 0.254 0.508)
			(layers "B.Cu" "B.Mask" "B.Paste")
			(net "P0V8_SERDES_VDDA_PEX1")
		)
	)
	(footprint ""
		(layer "B.Cu")
		(at 401.299934 -290.199826 90)
		(property "Reference" "C1953"
			(at 0 0 90)
			(layer "B.SilkS")
			(hide yes)
			(effects
				(font
					(size 1.27 1.27)
				)
				(justify mirror)
			)
		)
		(property "Value" ""
			(at 0 0 90)
			(layer "B.Fab")
			(effects
				(font
					(size 1.27 1.27)
				)
				(justify mirror)
			)
		)
		(duplicate_pad_numbers_are_jumpers no)
		(fp_line
			(start 0.299974 -0.150114)
			(end -0.299974 -0.150114)
			(stroke
				(width 0.1)
				(type default)
			)
			(layer "B.Fab")
		)
		(fp_line
			(start -0.299974 -0.150114)
			(end -0.299974 0.150114)
			(stroke
				(width 0.1)
				(type default)
			)
			(layer "B.Fab")
		)
		(fp_line
			(start 0.299974 0.150114)
			(end 0.299974 -0.150114)
			(stroke
				(width 0.1)
				(type default)
			)
			(layer "B.Fab")
		)
		(fp_line
			(start -0.299974 0.150114)
			(end 0.299974 0.150114)
			(stroke
				(width 0.1)
				(type default)
			)
			(layer "B.Fab")
		)
		(pad "1" smd rect
			(at 0.2667 0 270)
			(size 0.3048 0.381)
			(layers "B.Cu" "B.Mask" "B.Paste")
			(net "P0V8_SERDES_VDDA_PEX3")
		)
		(pad "2" smd rect
			(at -0.2667 0 270)
			(size 0.3048 0.381)
			(layers "B.Cu" "B.Mask" "B.Paste")
			(net "GND")
		)
	)
	(footprint ""
		(layer "B.Cu")
		(at 366.657382 -152.674066)
		(property "Reference" "R5624"
			(at 0 0 0)
			(layer "B.SilkS")
			(hide yes)
			(effects
				(font
					(size 1.27 1.27)
				)
				(justify mirror)
			)
		)
		(property "Value" ""
			(at 0 0 0)
			(layer "B.Fab")
			(effects
				(font
					(size 1.27 1.27)
				)
				(justify mirror)
			)
		)
		(duplicate_pad_numbers_are_jumpers no)
		(fp_line
			(start -0.7874 -0.4064)
			(end -0.7874 0.4064)
			(stroke
				(width 0.1524)
				(type default)
			)
			(layer "B.SilkS")
		)
		(fp_line
			(start -0.7874 0.4064)
			(end 0.7874 0.4064)
			(stroke
				(width 0.1524)
				(type default)
			)
			(layer "B.SilkS")
		)
		(fp_line
			(start 0.7874 -0.4064)
			(end -0.7874 -0.4064)
			(stroke
				(width 0.1524)
				(type default)
			)
			(layer "B.SilkS")
		)
		(fp_line
			(start 0.7874 0.4064)
			(end 0.7874 -0.4064)
			(stroke
				(width 0.1524)
				(type default)
			)
			(layer "B.SilkS")
		)
		(fp_line
			(start -0.67945 -0.3048)
			(end -0.67945 0.3048)
			(stroke
				(width 0.1)
				(type default)
			)
			(layer "B.Fab")
		)
		(fp_line
			(start -0.67945 0.3048)
			(end -0.120396 0.3048)
			(stroke
				(width 0.1)
				(type default)
			)
			(layer "B.Fab")
		)
		(fp_line
			(start -0.12065 -0.3048)
			(end -0.67945 -0.3048)
			(stroke
				(width 0.1)
				(type default)
			)
			(layer "B.Fab")
		)
		(fp_line
			(start -0.12065 -0.2794)
			(end -0.12065 -0.3048)
			(stroke
				(width 0.1)
				(type default)
			)
			(layer "B.Fab")
		)
		(fp_line
			(start -0.120396 0.2794)
			(end 0.12065 0.2794)
			(stroke
				(width 0.1)
				(type default)
			)
			(layer "B.Fab")
		)
		(fp_line
			(start -0.120396 0.3048)
			(end -0.120396 0.2794)
			(stroke
				(width 0.1)
				(type default)
			)
			(layer "B.Fab")
		)
		(fp_line
			(start 0.12065 -0.305054)
			(end 0.12065 -0.2794)
			(stroke
				(width 0.1)
				(type default)
			)
			(layer "B.Fab")
		)
		(fp_line
			(start 0.12065 -0.2794)
			(end -0.12065 -0.2794)
			(stroke
				(width 0.1)
				(type default)
			)
			(layer "B.Fab")
		)
		(fp_line
			(start 0.12065 0.2794)
			(end 0.12065 0.3048)
			(stroke
				(width 0.1)
				(type default)
			)
			(layer "B.Fab")
		)
		(fp_line
			(start 0.12065 0.3048)
			(end 0.67945 0.3048)
			(stroke
				(width 0.1)
				(type default)
			)
			(layer "B.Fab")
		)
		(fp_line
			(start 0.67945 -0.305054)
			(end 0.12065 -0.305054)
			(stroke
				(width 0.1)
				(type default)
			)
			(layer "B.Fab")
		)
		(fp_line
			(start 0.67945 0.3048)
			(end 0.67945 -0.305054)
			(stroke
				(width 0.1)
				(type default)
			)
			(layer "B.Fab")
		)
		(pad "1" smd circle
			(at 0.40005 0 180)
			(size 0 0)
			(layers "B.Cu" "B.Mask" "B.Paste")
			(net "NIC6_ADC_A0")
		)
		(pad "2" smd circle
			(at -0.40005 0 180)
			(size 0 0)
			(layers "B.Cu" "B.Mask" "B.Paste")
			(net "SMB_NIC6_ADC_SDA")
		)
	)
	(footprint ""
		(layer "B.Cu")
		(at 61.074808 -297.79976 -90)
		(property "Reference" "C1117"
			(at 0 0 90)
			(layer "B.SilkS")
			(hide yes)
			(effects
				(font
					(size 1.27 1.27)
				)
				(justify mirror)
			)
		)
		(property "Value" ""
			(at 0 0 90)
			(layer "B.Fab")
			(effects
				(font
					(size 1.27 1.27)
				)
				(justify mirror)
			)
		)
		(duplicate_pad_numbers_are_jumpers no)
		(fp_line
			(start -0.299974 0.150114)
			(end 0.299974 0.150114)
			(stroke
				(width 0.1)
				(type default)
			)
			(layer "B.Fab")
		)
		(fp_line
			(start 0.299974 0.150114)
			(end 0.299974 -0.150114)
			(stroke
				(width 0.1)
				(type default)
			)
			(layer "B.Fab")
		)
		(fp_line
			(start -0.299974 -0.150114)
			(end -0.299974 0.150114)
			(stroke
				(width 0.1)
				(type default)
			)
			(layer "B.Fab")
		)
		(fp_line
			(start 0.299974 -0.150114)
			(end -0.299974 -0.150114)
			(stroke
				(width 0.1)
				(type default)
			)
			(layer "B.Fab")
		)
		(pad "1" smd rect
			(at 0.2667 0 90)
			(size 0.3048 0.381)
			(layers "B.Cu" "B.Mask" "B.Paste")
			(net "P0V8_PEX0")
		)
		(pad "2" smd rect
			(at -0.2667 0 90)
			(size 0.3048 0.381)
			(layers "B.Cu" "B.Mask" "B.Paste")
			(net "GND")
		)
	)
	(footprint ""
		(layer "B.Cu")
		(at 73.271634 -115.608608)
		(property "Reference" "C874"
			(at 0 0 0)
			(layer "B.SilkS")
			(hide yes)
			(effects
				(font
					(size 1.27 1.27)
				)
				(justify mirror)
			)
		)
		(property "Value" ""
			(at 0 0 0)
			(layer "B.Fab")
			(effects
				(font
					(size 1.27 1.27)
				)
				(justify mirror)
			)
		)
		(duplicate_pad_numbers_are_jumpers no)
		(fp_line
			(start -0.7874 -0.4064)
			(end -0.7874 0.4064)
			(stroke
				(width 0.1524)
				(type default)
			)
			(layer "B.SilkS")
		)
		(fp_line
			(start -0.7874 0.4064)
			(end 0.7874 0.4064)
			(stroke
				(width 0.1524)
				(type default)
			)
			(layer "B.SilkS")
		)
		(fp_line
			(start 0.7874 -0.4064)
			(end -0.7874 -0.4064)
			(stroke
				(width 0.1524)
				(type default)
			)
			(layer "B.SilkS")
		)
		(fp_line
			(start 0.7874 0.4064)
			(end 0.7874 -0.4064)
			(stroke
				(width 0.1524)
				(type default)
			)
			(layer "B.SilkS")
		)
		(fp_line
			(start -0.67945 -0.3048)
			(end -0.67945 0.3048)
			(stroke
				(width 0.1)
				(type default)
			)
			(layer "B.Fab")
		)
		(fp_line
			(start -0.67945 0.3048)
			(end -0.120396 0.3048)
			(stroke
				(width 0.1)
				(type default)
			)
			(layer "B.Fab")
		)
		(fp_line
			(start -0.12065 -0.3048)
			(end -0.67945 -0.3048)
			(stroke
				(width 0.1)
				(type default)
			)
			(layer "B.Fab")
		)
		(fp_line
			(start -0.12065 -0.2794)
			(end -0.12065 -0.3048)
			(stroke
				(width 0.1)
				(type default)
			)
			(layer "B.Fab")
		)
		(fp_line
			(start -0.120396 0.2794)
			(end 0.12065 0.2794)
			(stroke
				(width 0.1)
				(type default)
			)
			(layer "B.Fab")
		)
		(fp_line
			(start -0.120396 0.3048)
			(end -0.120396 0.2794)
			(stroke
				(width 0.1)
				(type default)
			)
			(layer "B.Fab")
		)
		(fp_line
			(start 0.12065 -0.305054)
			(end 0.12065 -0.2794)
			(stroke
				(width 0.1)
				(type default)
			)
			(layer "B.Fab")
		)
		(fp_line
			(start 0.12065 -0.2794)
			(end -0.12065 -0.2794)
			(stroke
				(width 0.1)
				(type default)
			)
			(layer "B.Fab")
		)
		(fp_line
			(start 0.12065 0.2794)
			(end 0.12065 0.3048)
			(stroke
				(width 0.1)
				(type default)
			)
			(layer "B.Fab")
		)
		(fp_line
			(start 0.12065 0.3048)
			(end 0.67945 0.3048)
			(stroke
				(width 0.1)
				(type default)
			)
			(layer "B.Fab")
		)
		(fp_line
			(start 0.67945 -0.305054)
			(end 0.12065 -0.305054)
			(stroke
				(width 0.1)
				(type default)
			)
			(layer "B.Fab")
		)
		(fp_line
			(start 0.67945 0.3048)
			(end 0.67945 -0.305054)
			(stroke
				(width 0.1)
				(type default)
			)
			(layer "B.Fab")
		)
		(pad "1" smd circle
			(at 0.40005 0 180)
			(size 0 0)
			(layers "B.Cu" "B.Mask" "B.Paste")
			(net "P3V3_NIC1")
		)
		(pad "2" smd circle
			(at -0.40005 0 180)
			(size 0 0)
			(layers "B.Cu" "B.Mask" "B.Paste")
			(net "GND")
		)
	)
	(footprint ""
		(layer "B.Cu")
		(at 294.22471 -293.99992 -90)
		(property "Reference" "C1658"
			(at 0 0 90)
			(layer "B.SilkS")
			(hide yes)
			(effects
				(font
					(size 1.27 1.27)
				)
				(justify mirror)
			)
		)
		(property "Value" ""
			(at 0 0 90)
			(layer "B.Fab")
			(effects
				(font
					(size 1.27 1.27)
				)
				(justify mirror)
			)
		)
		(duplicate_pad_numbers_are_jumpers no)
		(fp_line
			(start -0.299974 0.150114)
			(end 0.299974 0.150114)
			(stroke
				(width 0.1)
				(type default)
			)
			(layer "B.Fab")
		)
		(fp_line
			(start 0.299974 0.150114)
			(end 0.299974 -0.150114)
			(stroke
				(width 0.1)
				(type default)
			)
			(layer "B.Fab")
		)
		(fp_line
			(start -0.299974 -0.150114)
			(end -0.299974 0.150114)
			(stroke
				(width 0.1)
				(type default)
			)
			(layer "B.Fab")
		)
		(fp_line
			(start 0.299974 -0.150114)
			(end -0.299974 -0.150114)
			(stroke
				(width 0.1)
				(type default)
			)
			(layer "B.Fab")
		)
		(pad "1" smd rect
			(at 0.2667 0 90)
			(size 0.3048 0.381)
			(layers "B.Cu" "B.Mask" "B.Paste")
			(net "P0V8_PEX2")
		)
		(pad "2" smd rect
			(at -0.2667 0 90)
			(size 0.3048 0.381)
			(layers "B.Cu" "B.Mask" "B.Paste")
			(net "GND")
		)
	)
	(footprint ""
		(layer "B.Cu")
		(at 176.699926 -290.199826 90)
		(property "Reference" "C1489"
			(at 0 0 90)
			(layer "B.SilkS")
			(hide yes)
			(effects
				(font
					(size 1.27 1.27)
				)
				(justify mirror)
			)
		)
		(property "Value" ""
			(at 0 0 90)
			(layer "B.Fab")
			(effects
				(font
					(size 1.27 1.27)
				)
				(justify mirror)
			)
		)
		(duplicate_pad_numbers_are_jumpers no)
		(fp_line
			(start 0.299974 -0.150114)
			(end -0.299974 -0.150114)
			(stroke
				(width 0.1)
				(type default)
			)
			(layer "B.Fab")
		)
		(fp_line
			(start -0.299974 -0.150114)
			(end -0.299974 0.150114)
			(stroke
				(width 0.1)
				(type default)
			)
			(layer "B.Fab")
		)
		(fp_line
			(start 0.299974 0.150114)
			(end 0.299974 -0.150114)
			(stroke
				(width 0.1)
				(type default)
			)
			(layer "B.Fab")
		)
		(fp_line
			(start -0.299974 0.150114)
			(end 0.299974 0.150114)
			(stroke
				(width 0.1)
				(type default)
			)
			(layer "B.Fab")
		)
		(pad "1" smd rect
			(at 0.2667 0 270)
			(size 0.3048 0.381)
			(layers "B.Cu" "B.Mask" "B.Paste")
			(net "P0V8_SERDES_VDDA_PEX1")
		)
		(pad "2" smd rect
			(at -0.2667 0 270)
			(size 0.3048 0.381)
			(layers "B.Cu" "B.Mask" "B.Paste")
			(net "GND")
		)
	)
	(footprint ""
		(layer "B.Cu")
		(at 331.343 -239.776)
		(property "Reference" "R6314"
			(at 0 0 0)
			(layer "B.SilkS")
			(hide yes)
			(effects
				(font
					(size 1.27 1.27)
				)
				(justify mirror)
			)
		)
		(property "Value" ""
			(at 0 0 0)
			(layer "B.Fab")
			(effects
				(font
					(size 1.27 1.27)
				)
				(justify mirror)
			)
		)
		(duplicate_pad_numbers_are_jumpers no)
		(fp_line
			(start -0.7874 -0.4064)
			(end -0.7874 0.4064)
			(stroke
				(width 0.1524)
				(type default)
			)
			(layer "B.SilkS")
		)
		(fp_line
			(start -0.7874 0.4064)
			(end 0.7874 0.4064)
			(stroke
				(width 0.1524)
				(type default)
			)
			(layer "B.SilkS")
		)
		(fp_line
			(start 0.7874 -0.4064)
			(end -0.7874 -0.4064)
			(stroke
				(width 0.1524)
				(type default)
			)
			(layer "B.SilkS")
		)
		(fp_line
			(start 0.7874 0.4064)
			(end 0.7874 -0.4064)
			(stroke
				(width 0.1524)
				(type default)
			)
			(layer "B.SilkS")
		)
		(fp_line
			(start -0.67945 -0.3048)
			(end -0.67945 0.3048)
			(stroke
				(width 0.1)
				(type default)
			)
			(layer "B.Fab")
		)
		(fp_line
			(start -0.67945 0.3048)
			(end -0.120396 0.3048)
			(stroke
				(width 0.1)
				(type default)
			)
			(layer "B.Fab")
		)
		(fp_line
			(start -0.12065 -0.3048)
			(end -0.67945 -0.3048)
			(stroke
				(width 0.1)
				(type default)
			)
			(layer "B.Fab")
		)
		(fp_line
			(start -0.12065 -0.2794)
			(end -0.12065 -0.3048)
			(stroke
				(width 0.1)
				(type default)
			)
			(layer "B.Fab")
		)
		(fp_line
			(start -0.120396 0.2794)
			(end 0.12065 0.2794)
			(stroke
				(width 0.1)
				(type default)
			)
			(layer "B.Fab")
		)
		(fp_line
			(start -0.120396 0.3048)
			(end -0.120396 0.2794)
			(stroke
				(width 0.1)
				(type default)
			)
			(layer "B.Fab")
		)
		(fp_line
			(start 0.12065 -0.305054)
			(end 0.12065 -0.2794)
			(stroke
				(width 0.1)
				(type default)
			)
			(layer "B.Fab")
		)
		(fp_line
			(start 0.12065 -0.2794)
			(end -0.12065 -0.2794)
			(stroke
				(width 0.1)
				(type default)
			)
			(layer "B.Fab")
		)
		(fp_line
			(start 0.12065 0.2794)
			(end 0.12065 0.3048)
			(stroke
				(width 0.1)
				(type default)
			)
			(layer "B.Fab")
		)
		(fp_line
			(start 0.12065 0.3048)
			(end 0.67945 0.3048)
			(stroke
				(width 0.1)
				(type default)
			)
			(layer "B.Fab")
		)
		(fp_line
			(start 0.67945 -0.305054)
			(end 0.12065 -0.305054)
			(stroke
				(width 0.1)
				(type default)
			)
			(layer "B.Fab")
		)
		(fp_line
			(start 0.67945 0.3048)
			(end 0.67945 -0.305054)
			(stroke
				(width 0.1)
				(type default)
			)
			(layer "B.Fab")
		)
		(pad "1" smd circle
			(at 0.40005 0 180)
			(size 0 0)
			(layers "B.Cu" "B.Mask" "B.Paste")
			(net "MB_SWB_PWRGD_R")
		)
		(pad "2" smd circle
			(at -0.40005 0 180)
			(size 0 0)
			(layers "B.Cu" "B.Mask" "B.Paste")
			(net "GND")
		)
	)
	(footprint ""
		(layer "B.Cu")
		(at 116.128292 -304.157634)
		(property "Reference" "PR78"
			(at 0 0 0)
			(layer "B.SilkS")
			(hide yes)
			(effects
				(font
					(size 1.27 1.27)
				)
				(justify mirror)
			)
		)
		(property "Value" ""
			(at 0 0 0)
			(layer "B.Fab")
			(effects
				(font
					(size 1.27 1.27)
				)
				(justify mirror)
			)
		)
		(duplicate_pad_numbers_are_jumpers no)
		(fp_line
			(start -0.7874 -0.4064)
			(end -0.7874 0.4064)
			(stroke
				(width 0.1524)
				(type default)
			)
			(layer "B.SilkS")
		)
		(fp_line
			(start -0.7874 0.4064)
			(end 0.7874 0.4064)
			(stroke
				(width 0.1524)
				(type default)
			)
			(layer "B.SilkS")
		)
		(fp_line
			(start 0.7874 -0.4064)
			(end -0.7874 -0.4064)
			(stroke
				(width 0.1524)
				(type default)
			)
			(layer "B.SilkS")
		)
		(fp_line
			(start 0.7874 0.4064)
			(end 0.7874 -0.4064)
			(stroke
				(width 0.1524)
				(type default)
			)
			(layer "B.SilkS")
		)
		(fp_line
			(start -0.67945 -0.3048)
			(end -0.67945 0.3048)
			(stroke
				(width 0.1)
				(type default)
			)
			(layer "B.Fab")
		)
		(fp_line
			(start -0.67945 0.3048)
			(end -0.120396 0.3048)
			(stroke
				(width 0.1)
				(type default)
			)
			(layer "B.Fab")
		)
		(fp_line
			(start -0.12065 -0.3048)
			(end -0.67945 -0.3048)
			(stroke
				(width 0.1)
				(type default)
			)
			(layer "B.Fab")
		)
		(fp_line
			(start -0.12065 -0.2794)
			(end -0.12065 -0.3048)
			(stroke
				(width 0.1)
				(type default)
			)
			(layer "B.Fab")
		)
		(fp_line
			(start -0.120396 0.2794)
			(end 0.12065 0.2794)
			(stroke
				(width 0.1)
				(type default)
			)
			(layer "B.Fab")
		)
		(fp_line
			(start -0.120396 0.3048)
			(end -0.120396 0.2794)
			(stroke
				(width 0.1)
				(type default)
			)
			(layer "B.Fab")
		)
		(fp_line
			(start 0.12065 -0.305054)
			(end 0.12065 -0.2794)
			(stroke
				(width 0.1)
				(type default)
			)
			(layer "B.Fab")
		)
		(fp_line
			(start 0.12065 -0.2794)
			(end -0.12065 -0.2794)
			(stroke
				(width 0.1)
				(type default)
			)
			(layer "B.Fab")
		)
		(fp_line
			(start 0.12065 0.2794)
			(end 0.12065 0.3048)
			(stroke
				(width 0.1)
				(type default)
			)
			(layer "B.Fab")
		)
		(fp_line
			(start 0.12065 0.3048)
			(end 0.67945 0.3048)
			(stroke
				(width 0.1)
				(type default)
			)
			(layer "B.Fab")
		)
		(fp_line
			(start 0.67945 -0.305054)
			(end 0.12065 -0.305054)
			(stroke
				(width 0.1)
				(type default)
			)
			(layer "B.Fab")
		)
		(fp_line
			(start 0.67945 0.3048)
			(end 0.67945 -0.305054)
			(stroke
				(width 0.1)
				(type default)
			)
			(layer "B.Fab")
		)
		(pad "1" smd circle
			(at 0.40005 0 180)
			(size 0 0)
			(layers "B.Cu" "B.Mask" "B.Paste")
			(net "SH_P0V8_PEX0_RGND0")
		)
		(pad "2" smd circle
			(at -0.40005 0 180)
			(size 0 0)
			(layers "B.Cu" "B.Mask" "B.Paste")
			(net "GND")
		)
	)
)
